(kicad_pcb
	(version 20260206)
	(generator "pcbnew")
	(generator_version "10.0")
	(general
		(thickness 1.6)
		(legacy_teardrops no)
	)
	(paper "A4")
	(title_block
		(title "03242023_DA0F0TMBIJ0_F0T_Motherboard_J_brd_V01_OCP.brd")
		(comment 1 "Grand Teton / footprints 4059-4064 of 6105")
	)
	(layers
		(0 "F.Cu" signal "TOP")
		(4 "In1.Cu" signal "GND")
		(6 "In2.Cu" signal "IN1")
		(8 "In3.Cu" signal "GND1")
		(10 "In4.Cu" signal "IN2")
		(12 "In5.Cu" signal "GND2")
		(14 "In6.Cu" signal "IN3")
		(16 "In7.Cu" signal "GND3")
		(18 "In8.Cu" signal "VCC")
		(20 "In9.Cu" signal "VCC1")
		(22 "In10.Cu" signal "GND4")
		(24 "In11.Cu" signal "IN4")
		(26 "In12.Cu" signal "GND5")
		(28 "In13.Cu" signal "IN5")
		(30 "In14.Cu" signal "GND6")
		(32 "In15.Cu" signal "IN6")
		(34 "In16.Cu" signal "GND7")
		(2 "B.Cu" signal "BOTTOM")
		(9 "F.Adhes" user "F.Adhesive")
		(11 "B.Adhes" user "B.Adhesive")
		(13 "F.Paste" user "Package Geometry/Pastemask Top")
		(15 "B.Paste" user "Package Geometry/Pastemask Bottom")
		(5 "F.SilkS" user "Ref Des/Silkscreen Top")
		(7 "B.SilkS" user "Ref Des/Silkscreen Bottom")
		(1 "F.Mask" user "Board Geometry/Soldermask Top")
		(3 "B.Mask" user "Board Geometry/Soldermask Bottom")
		(17 "Dwgs.User" user "User.Drawings")
		(19 "Cmts.User" user "User.Comments")
		(21 "Eco1.User" user "User.Eco1")
		(23 "Eco2.User" user "User.Eco2")
		(25 "Edge.Cuts" user "Board Geometry/Outline")
		(27 "Margin" user)
		(31 "F.CrtYd" user "Package Geometry/Place Bound Top")
		(29 "B.CrtYd" user "Package Geometry/Place Bound Bottom")
		(35 "F.Fab" user "Ref Des/Assembly Top")
		(33 "B.Fab" user "Ref Des/Assembly Bottom")
	)
	(footprint ""
		(layer "F.Cu")
		(at 226.503738 -220.815916 90)
		(property "Reference" "R996"
			(at 0 0 90)
			(layer "F.SilkS")
			(hide yes)
			(effects
				(font
					(size 1.27 1.27)
				)
			)
		)
		(property "Value" ""
			(at 0 0 90)
			(layer "F.Fab")
			(effects
				(font
					(size 1.27 1.27)
				)
			)
		)
		(duplicate_pad_numbers_are_jumpers no)
		(fp_line
			(start 0.7874 -0.4064)
			(end 0.7874 0.4064)
			(stroke
				(width 0.1524)
				(type default)
			)
			(layer "F.SilkS")
		)
		(fp_line
			(start -0.7874 -0.4064)
			(end 0.7874 -0.4064)
			(stroke
				(width 0.1524)
				(type default)
			)
			(layer "F.SilkS")
		)
		(fp_line
			(start 0.7874 0.4064)
			(end -0.7874 0.4064)
			(stroke
				(width 0.1524)
				(type default)
			)
			(layer "F.SilkS")
		)
		(fp_line
			(start -0.7874 0.4064)
			(end -0.7874 -0.4064)
			(stroke
				(width 0.1524)
				(type default)
			)
			(layer "F.SilkS")
		)
		(fp_line
			(start -0.12065 -0.305054)
			(end -0.12065 -0.2794)
			(stroke
				(width 0.1)
				(type default)
			)
			(layer "F.Fab")
		)
		(fp_line
			(start -0.67945 -0.305054)
			(end -0.12065 -0.305054)
			(stroke
				(width 0.1)
				(type default)
			)
			(layer "F.Fab")
		)
		(fp_line
			(start 0.67945 -0.3048)
			(end 0.67945 0.3048)
			(stroke
				(width 0.1)
				(type default)
			)
			(layer "F.Fab")
		)
		(fp_line
			(start 0.12065 -0.3048)
			(end 0.67945 -0.3048)
			(stroke
				(width 0.1)
				(type default)
			)
			(layer "F.Fab")
		)
		(fp_line
			(start 0.12065 -0.2794)
			(end 0.12065 -0.3048)
			(stroke
				(width 0.1)
				(type default)
			)
			(layer "F.Fab")
		)
		(fp_line
			(start -0.12065 -0.2794)
			(end 0.12065 -0.2794)
			(stroke
				(width 0.1)
				(type default)
			)
			(layer "F.Fab")
		)
		(fp_line
			(start 0.120396 0.2794)
			(end -0.12065 0.2794)
			(stroke
				(width 0.1)
				(type default)
			)
			(layer "F.Fab")
		)
		(fp_line
			(start -0.12065 0.2794)
			(end -0.12065 0.3048)
			(stroke
				(width 0.1)
				(type default)
			)
			(layer "F.Fab")
		)
		(fp_line
			(start 0.67945 0.3048)
			(end 0.120396 0.3048)
			(stroke
				(width 0.1)
				(type default)
			)
			(layer "F.Fab")
		)
		(fp_line
			(start 0.120396 0.3048)
			(end 0.120396 0.2794)
			(stroke
				(width 0.1)
				(type default)
			)
			(layer "F.Fab")
		)
		(fp_line
			(start -0.12065 0.3048)
			(end -0.67945 0.3048)
			(stroke
				(width 0.1)
				(type default)
			)
			(layer "F.Fab")
		)
		(fp_line
			(start -0.67945 0.3048)
			(end -0.67945 -0.305054)
			(stroke
				(width 0.1)
				(type default)
			)
			(layer "F.Fab")
		)
		(pad "1" smd circle
			(at -0.40005 0 90)
			(size 0 0)
			(layers "F.Cu" "F.Mask" "F.Paste")
			(net "SMB_S3M_CPU1_SDA")
		)
		(pad "2" smd circle
			(at 0.40005 0 90)
			(size 0 0)
			(layers "F.Cu" "F.Mask" "F.Paste")
			(net "SMB_S3M_CPU1_R_SDA")
		)
	)
	(footprint ""
		(layer "F.Cu")
		(at 120.438926 -119.810784 -90)
		(property "Reference" "R859"
			(at 0 0 270)
			(layer "F.SilkS")
			(hide yes)
			(effects
				(font
					(size 1.27 1.27)
				)
			)
		)
		(property "Value" ""
			(at 0 0 270)
			(layer "F.Fab")
			(effects
				(font
					(size 1.27 1.27)
				)
			)
		)
		(duplicate_pad_numbers_are_jumpers no)
		(fp_line
			(start -0.7874 0.4064)
			(end -0.7874 -0.4064)
			(stroke
				(width 0.1524)
				(type default)
			)
			(layer "F.SilkS")
		)
		(fp_line
			(start 0.7874 0.4064)
			(end -0.7874 0.4064)
			(stroke
				(width 0.1524)
				(type default)
			)
			(layer "F.SilkS")
		)
		(fp_line
			(start -0.7874 -0.4064)
			(end 0.7874 -0.4064)
			(stroke
				(width 0.1524)
				(type default)
			)
			(layer "F.SilkS")
		)
		(fp_line
			(start 0.7874 -0.4064)
			(end 0.7874 0.4064)
			(stroke
				(width 0.1524)
				(type default)
			)
			(layer "F.SilkS")
		)
		(fp_line
			(start -0.67945 0.3048)
			(end -0.67945 -0.305054)
			(stroke
				(width 0.1)
				(type default)
			)
			(layer "F.Fab")
		)
		(fp_line
			(start -0.12065 0.3048)
			(end -0.67945 0.3048)
			(stroke
				(width 0.1)
				(type default)
			)
			(layer "F.Fab")
		)
		(fp_line
			(start 0.120396 0.3048)
			(end 0.120396 0.2794)
			(stroke
				(width 0.1)
				(type default)
			)
			(layer "F.Fab")
		)
		(fp_line
			(start 0.67945 0.3048)
			(end 0.120396 0.3048)
			(stroke
				(width 0.1)
				(type default)
			)
			(layer "F.Fab")
		)
		(fp_line
			(start -0.12065 0.2794)
			(end -0.12065 0.3048)
			(stroke
				(width 0.1)
				(type default)
			)
			(layer "F.Fab")
		)
		(fp_line
			(start 0.120396 0.2794)
			(end -0.12065 0.2794)
			(stroke
				(width 0.1)
				(type default)
			)
			(layer "F.Fab")
		)
		(fp_line
			(start -0.12065 -0.2794)
			(end 0.12065 -0.2794)
			(stroke
				(width 0.1)
				(type default)
			)
			(layer "F.Fab")
		)
		(fp_line
			(start 0.12065 -0.2794)
			(end 0.12065 -0.3048)
			(stroke
				(width 0.1)
				(type default)
			)
			(layer "F.Fab")
		)
		(fp_line
			(start 0.12065 -0.3048)
			(end 0.67945 -0.3048)
			(stroke
				(width 0.1)
				(type default)
			)
			(layer "F.Fab")
		)
		(fp_line
			(start 0.67945 -0.3048)
			(end 0.67945 0.3048)
			(stroke
				(width 0.1)
				(type default)
			)
			(layer "F.Fab")
		)
		(fp_line
			(start -0.67945 -0.305054)
			(end -0.12065 -0.305054)
			(stroke
				(width 0.1)
				(type default)
			)
			(layer "F.Fab")
		)
		(fp_line
			(start -0.12065 -0.305054)
			(end -0.12065 -0.2794)
			(stroke
				(width 0.1)
				(type default)
			)
			(layer "F.Fab")
		)
		(pad "1" smd circle
			(at -0.40005 0 270)
			(size 0 0)
			(layers "F.Cu" "F.Mask" "F.Paste")
			(net "RST_CPU1_DRAM_AB_N")
		)
		(pad "2" smd circle
			(at 0.40005 0 270)
			(size 0 0)
			(layers "F.Cu" "F.Mask" "F.Paste")
			(net "RST_CPU1_DRAM_AB_PLD_N")
		)
	)
	(footprint ""
		(layer "F.Cu")
		(at 186.23788 -99.659948 -90)
		(property "Reference" "R992"
			(at 0 0 270)
			(layer "F.SilkS")
			(hide yes)
			(effects
				(font
					(size 1.27 1.27)
				)
			)
		)
		(property "Value" ""
			(at 0 0 270)
			(layer "F.Fab")
			(effects
				(font
					(size 1.27 1.27)
				)
			)
		)
		(duplicate_pad_numbers_are_jumpers no)
		(fp_line
			(start -0.7874 0.4064)
			(end -0.7874 -0.4064)
			(stroke
				(width 0.1524)
				(type default)
			)
			(layer "F.SilkS")
		)
		(fp_line
			(start 0.7874 0.4064)
			(end -0.7874 0.4064)
			(stroke
				(width 0.1524)
				(type default)
			)
			(layer "F.SilkS")
		)
		(fp_line
			(start -0.7874 -0.4064)
			(end 0.7874 -0.4064)
			(stroke
				(width 0.1524)
				(type default)
			)
			(layer "F.SilkS")
		)
		(fp_line
			(start 0.7874 -0.4064)
			(end 0.7874 0.4064)
			(stroke
				(width 0.1524)
				(type default)
			)
			(layer "F.SilkS")
		)
		(fp_line
			(start -0.67945 0.3048)
			(end -0.67945 -0.305054)
			(stroke
				(width 0.1)
				(type default)
			)
			(layer "F.Fab")
		)
		(fp_line
			(start -0.12065 0.3048)
			(end -0.67945 0.3048)
			(stroke
				(width 0.1)
				(type default)
			)
			(layer "F.Fab")
		)
		(fp_line
			(start 0.120396 0.3048)
			(end 0.120396 0.2794)
			(stroke
				(width 0.1)
				(type default)
			)
			(layer "F.Fab")
		)
		(fp_line
			(start 0.67945 0.3048)
			(end 0.120396 0.3048)
			(stroke
				(width 0.1)
				(type default)
			)
			(layer "F.Fab")
		)
		(fp_line
			(start -0.12065 0.2794)
			(end -0.12065 0.3048)
			(stroke
				(width 0.1)
				(type default)
			)
			(layer "F.Fab")
		)
		(fp_line
			(start 0.120396 0.2794)
			(end -0.12065 0.2794)
			(stroke
				(width 0.1)
				(type default)
			)
			(layer "F.Fab")
		)
		(fp_line
			(start -0.12065 -0.2794)
			(end 0.12065 -0.2794)
			(stroke
				(width 0.1)
				(type default)
			)
			(layer "F.Fab")
		)
		(fp_line
			(start 0.12065 -0.2794)
			(end 0.12065 -0.3048)
			(stroke
				(width 0.1)
				(type default)
			)
			(layer "F.Fab")
		)
		(fp_line
			(start 0.12065 -0.3048)
			(end 0.67945 -0.3048)
			(stroke
				(width 0.1)
				(type default)
			)
			(layer "F.Fab")
		)
		(fp_line
			(start 0.67945 -0.3048)
			(end 0.67945 0.3048)
			(stroke
				(width 0.1)
				(type default)
			)
			(layer "F.Fab")
		)
		(fp_line
			(start -0.67945 -0.305054)
			(end -0.12065 -0.305054)
			(stroke
				(width 0.1)
				(type default)
			)
			(layer "F.Fab")
		)
		(fp_line
			(start -0.12065 -0.305054)
			(end -0.12065 -0.2794)
			(stroke
				(width 0.1)
				(type default)
			)
			(layer "F.Fab")
		)
		(pad "1" smd circle
			(at -0.40005 0 270)
			(size 0 0)
			(layers "F.Cu" "F.Mask" "F.Paste")
			(net "PWRGD_CPU0_LVC1_R")
		)
		(pad "2" smd circle
			(at 0.40005 0 270)
			(size 0 0)
			(layers "F.Cu" "F.Mask" "F.Paste")
			(net "GND")
		)
	)
	(footprint ""
		(layer "F.Cu")
		(at 14.01826 -92.687648 -90)
		(property "Reference" "R3666"
			(at 0 0 270)
			(layer "F.SilkS")
			(hide yes)
			(effects
				(font
					(size 1.27 1.27)
				)
			)
		)
		(property "Value" ""
			(at 0 0 270)
			(layer "F.Fab")
			(effects
				(font
					(size 1.27 1.27)
				)
			)
		)
		(duplicate_pad_numbers_are_jumpers no)
		(fp_line
			(start -0.7874 0.4064)
			(end -0.7874 -0.4064)
			(stroke
				(width 0.1524)
				(type default)
			)
			(layer "F.SilkS")
		)
		(fp_line
			(start 0.7874 0.4064)
			(end -0.7874 0.4064)
			(stroke
				(width 0.1524)
				(type default)
			)
			(layer "F.SilkS")
		)
		(fp_line
			(start -0.7874 -0.4064)
			(end 0.7874 -0.4064)
			(stroke
				(width 0.1524)
				(type default)
			)
			(layer "F.SilkS")
		)
		(fp_line
			(start 0.7874 -0.4064)
			(end 0.7874 0.4064)
			(stroke
				(width 0.1524)
				(type default)
			)
			(layer "F.SilkS")
		)
		(fp_line
			(start -0.67945 0.3048)
			(end -0.67945 -0.305054)
			(stroke
				(width 0.1)
				(type default)
			)
			(layer "F.Fab")
		)
		(fp_line
			(start -0.12065 0.3048)
			(end -0.67945 0.3048)
			(stroke
				(width 0.1)
				(type default)
			)
			(layer "F.Fab")
		)
		(fp_line
			(start 0.120396 0.3048)
			(end 0.120396 0.2794)
			(stroke
				(width 0.1)
				(type default)
			)
			(layer "F.Fab")
		)
		(fp_line
			(start 0.67945 0.3048)
			(end 0.120396 0.3048)
			(stroke
				(width 0.1)
				(type default)
			)
			(layer "F.Fab")
		)
		(fp_line
			(start -0.12065 0.2794)
			(end -0.12065 0.3048)
			(stroke
				(width 0.1)
				(type default)
			)
			(layer "F.Fab")
		)
		(fp_line
			(start 0.120396 0.2794)
			(end -0.12065 0.2794)
			(stroke
				(width 0.1)
				(type default)
			)
			(layer "F.Fab")
		)
		(fp_line
			(start -0.12065 -0.2794)
			(end 0.12065 -0.2794)
			(stroke
				(width 0.1)
				(type default)
			)
			(layer "F.Fab")
		)
		(fp_line
			(start 0.12065 -0.2794)
			(end 0.12065 -0.3048)
			(stroke
				(width 0.1)
				(type default)
			)
			(layer "F.Fab")
		)
		(fp_line
			(start 0.12065 -0.3048)
			(end 0.67945 -0.3048)
			(stroke
				(width 0.1)
				(type default)
			)
			(layer "F.Fab")
		)
		(fp_line
			(start 0.67945 -0.3048)
			(end 0.67945 0.3048)
			(stroke
				(width 0.1)
				(type default)
			)
			(layer "F.Fab")
		)
		(fp_line
			(start -0.67945 -0.305054)
			(end -0.12065 -0.305054)
			(stroke
				(width 0.1)
				(type default)
			)
			(layer "F.Fab")
		)
		(fp_line
			(start -0.12065 -0.305054)
			(end -0.12065 -0.2794)
			(stroke
				(width 0.1)
				(type default)
			)
			(layer "F.Fab")
		)
		(pad "1" smd circle
			(at -0.40005 0 270)
			(size 0 0)
			(layers "F.Cu" "F.Mask" "F.Paste")
			(net "USB_HUB_TEST")
		)
		(pad "2" smd circle
			(at 0.40005 0 270)
			(size 0 0)
			(layers "F.Cu" "F.Mask" "F.Paste")
			(net "GND")
		)
	)
	(footprint ""
		(layer "F.Cu")
		(at 282.73756 -424.558714 90)
		(property "Reference" "R4693"
			(at 0 0 90)
			(layer "F.SilkS")
			(hide yes)
			(effects
				(font
					(size 1.27 1.27)
				)
			)
		)
		(property "Value" ""
			(at 0 0 90)
			(layer "F.Fab")
			(effects
				(font
					(size 1.27 1.27)
				)
			)
		)
		(duplicate_pad_numbers_are_jumpers no)
		(fp_line
			(start 0.7874 -0.4064)
			(end 0.7874 0.4064)
			(stroke
				(width 0.1524)
				(type default)
			)
			(layer "F.SilkS")
		)
		(fp_line
			(start -0.7874 -0.4064)
			(end 0.7874 -0.4064)
			(stroke
				(width 0.1524)
				(type default)
			)
			(layer "F.SilkS")
		)
		(fp_line
			(start 0.7874 0.4064)
			(end -0.7874 0.4064)
			(stroke
				(width 0.1524)
				(type default)
			)
			(layer "F.SilkS")
		)
		(fp_line
			(start -0.7874 0.4064)
			(end -0.7874 -0.4064)
			(stroke
				(width 0.1524)
				(type default)
			)
			(layer "F.SilkS")
		)
		(fp_line
			(start -0.12065 -0.305054)
			(end -0.12065 -0.2794)
			(stroke
				(width 0.1)
				(type default)
			)
			(layer "F.Fab")
		)
		(fp_line
			(start -0.67945 -0.305054)
			(end -0.12065 -0.305054)
			(stroke
				(width 0.1)
				(type default)
			)
			(layer "F.Fab")
		)
		(fp_line
			(start 0.67945 -0.3048)
			(end 0.67945 0.3048)
			(stroke
				(width 0.1)
				(type default)
			)
			(layer "F.Fab")
		)
		(fp_line
			(start 0.12065 -0.3048)
			(end 0.67945 -0.3048)
			(stroke
				(width 0.1)
				(type default)
			)
			(layer "F.Fab")
		)
		(fp_line
			(start 0.12065 -0.2794)
			(end 0.12065 -0.3048)
			(stroke
				(width 0.1)
				(type default)
			)
			(layer "F.Fab")
		)
		(fp_line
			(start -0.12065 -0.2794)
			(end 0.12065 -0.2794)
			(stroke
				(width 0.1)
				(type default)
			)
			(layer "F.Fab")
		)
		(fp_line
			(start 0.120396 0.2794)
			(end -0.12065 0.2794)
			(stroke
				(width 0.1)
				(type default)
			)
			(layer "F.Fab")
		)
		(fp_line
			(start -0.12065 0.2794)
			(end -0.12065 0.3048)
			(stroke
				(width 0.1)
				(type default)
			)
			(layer "F.Fab")
		)
		(fp_line
			(start 0.67945 0.3048)
			(end 0.120396 0.3048)
			(stroke
				(width 0.1)
				(type default)
			)
			(layer "F.Fab")
		)
		(fp_line
			(start 0.120396 0.3048)
			(end 0.120396 0.2794)
			(stroke
				(width 0.1)
				(type default)
			)
			(layer "F.Fab")
		)
		(fp_line
			(start -0.12065 0.3048)
			(end -0.67945 0.3048)
			(stroke
				(width 0.1)
				(type default)
			)
			(layer "F.Fab")
		)
		(fp_line
			(start -0.67945 0.3048)
			(end -0.67945 -0.305054)
			(stroke
				(width 0.1)
				(type default)
			)
			(layer "F.Fab")
		)
		(pad "1" smd circle
			(at -0.40005 0 90)
			(size 0 0)
			(layers "F.Cu" "F.Mask" "F.Paste")
			(net "HSC_CSOUT")
		)
		(pad "2" smd circle
			(at 0.40005 0 90)
			(size 0 0)
			(layers "F.Cu" "F.Mask" "F.Paste")
			(net "HSC_D_OC")
		)
	)
	(footprint ""
		(layer "F.Cu")
		(at 231.976422 -117.710712 -90)
		(property "Reference" "R1276"
			(at 0 0 270)
			(layer "F.SilkS")
			(hide yes)
			(effects
				(font
					(size 1.27 1.27)
				)
			)
		)
		(property "Value" ""
			(at 0 0 270)
			(layer "F.Fab")
			(effects
				(font
					(size 1.27 1.27)
				)
			)
		)
		(duplicate_pad_numbers_are_jumpers no)
		(fp_line
			(start 0.418592 0.4064)
			(end -0.373888 0.4064)
			(stroke
				(width 0.1524)
				(type default)
			)
			(layer "F.SilkS")
		)
		(fp_line
			(start -0.7874 -0.006858)
			(end -0.7874 -0.4064)
			(stroke
				(width 0.1524)
				(type default)
			)
			(layer "F.SilkS")
		)
		(fp_line
			(start -0.7874 -0.4064)
			(end 0.7874 -0.4064)
			(stroke
				(width 0.1524)
				(type default)
			)
			(layer "F.SilkS")
		)
		(fp_line
			(start 0.7874 -0.4064)
			(end 0.7874 0.079502)
			(stroke
				(width 0.1524)
				(type default)
			)
			(layer "F.SilkS")
		)
		(fp_line
			(start -0.67945 0.3048)
			(end -0.67945 -0.305054)
			(stroke
				(width 0.1)
				(type default)
			)
			(layer "F.Fab")
		)
		(fp_line
			(start -0.12065 0.3048)
			(end -0.67945 0.3048)
			(stroke
				(width 0.1)
				(type default)
			)
			(layer "F.Fab")
		)
		(fp_line
			(start 0.120396 0.3048)
			(end 0.120396 0.2794)
			(stroke
				(width 0.1)
				(type default)
			)
			(layer "F.Fab")
		)
		(fp_line
			(start 0.67945 0.3048)
			(end 0.120396 0.3048)
			(stroke
				(width 0.1)
				(type default)
			)
			(layer "F.Fab")
		)
		(fp_line
			(start -0.12065 0.2794)
			(end -0.12065 0.3048)
			(stroke
				(width 0.1)
				(type default)
			)
			(layer "F.Fab")
		)
		(fp_line
			(start 0.120396 0.2794)
			(end -0.12065 0.2794)
			(stroke
				(width 0.1)
				(type default)
			)
			(layer "F.Fab")
		)
		(fp_line
			(start -0.12065 -0.2794)
			(end 0.12065 -0.2794)
			(stroke
				(width 0.1)
				(type default)
			)
			(layer "F.Fab")
		)
		(fp_line
			(start 0.12065 -0.2794)
			(end 0.12065 -0.3048)
			(stroke
				(width 0.1)
				(type default)
			)
			(layer "F.Fab")
		)
		(fp_line
			(start 0.12065 -0.3048)
			(end 0.67945 -0.3048)
			(stroke
				(width 0.1)
				(type default)
			)
			(layer "F.Fab")
		)
		(fp_line
			(start 0.67945 -0.3048)
			(end 0.67945 0.3048)
			(stroke
				(width 0.1)
				(type default)
			)
			(layer "F.Fab")
		)
		(fp_line
			(start -0.67945 -0.305054)
			(end -0.12065 -0.305054)
			(stroke
				(width 0.1)
				(type default)
			)
			(layer "F.Fab")
		)
		(fp_line
			(start -0.12065 -0.305054)
			(end -0.12065 -0.2794)
			(stroke
				(width 0.1)
				(type default)
			)
			(layer "F.Fab")
		)
		(pad "1" smd circle
			(at -0.40005 0 270)
			(size 0 0)
			(layers "F.Cu" "F.Mask" "F.Paste")
			(net "CLK_100M_OCP_SFF_3_R_DN")
		)
		(pad "2" smd circle
			(at 0.40005 0 270)
			(size 0 0)
			(layers "F.Cu" "F.Mask" "F.Paste")
			(net "CLK_100M_OCP_SFF_3_DN")
		)
	)
)
